(kicad_pcb
	(version 20260206)
	(generator "pcbnew")
	(generator_version "10.0")
	(general
		(thickness 1.6)
		(legacy_teardrops no)
	)
	(paper "A4")
	(title_block
		(title "timecard-production-celestica-r4006 — R4006-B0001-02_R01.brd")
		(comment 1 "Time Appliance Project (Time Card) / footprints 758-761 of 1113")
	)
	(layers
		(0 "F.Cu" signal "TOP")
		(4 "In1.Cu" signal "L02_GND1")
		(6 "In2.Cu" signal "L03_SIG1")
		(8 "In3.Cu" signal "L04_GND2")
		(10 "In4.Cu" signal "L05_VCC1")
		(12 "In5.Cu" signal "L06_VCC2")
		(14 "In6.Cu" signal "L07_GND3")
		(16 "In7.Cu" signal "L08_SIG2")
		(18 "In8.Cu" signal "L09_GND4")
		(2 "B.Cu" signal "BOTTOM")
		(9 "F.Adhes" user "F.Adhesive")
		(11 "B.Adhes" user "B.Adhesive")
		(13 "F.Paste" user "Package Geometry/Pastemask Top")
		(15 "B.Paste" user "Package Geometry/Pastemask Bottom")
		(5 "F.SilkS" user "Ref Des/Silkscreen Top")
		(7 "B.SilkS" user "Ref Des/Silkscreen Bottom")
		(1 "F.Mask" user "Board Geometry/Soldermask Top")
		(3 "B.Mask" user "Board Geometry/Soldermask Bottom")
		(17 "Dwgs.User" user "User.Drawings")
		(19 "Cmts.User" user "User.Comments")
		(21 "Eco1.User" user "User.Eco1")
		(23 "Eco2.User" user "User.Eco2")
		(25 "Edge.Cuts" user "Board Geometry/Outline")
		(27 "Margin" user)
		(31 "F.CrtYd" user "Package Geometry/Place Bound Top")
		(29 "B.CrtYd" user "Package Geometry/Place Bound Bottom")
		(35 "F.Fab" user "Ref Des/Assembly Top")
		(33 "B.Fab" user "Ref Des/Assembly Bottom")
	)
	(footprint ""
		(layer "B.Cu")
		(at 101.4476 -82.2706 180)
		(property "Reference" "R458"
			(at -0.0254 -1.66497 0)
			(unlocked yes)
			(layer "B.SilkS")
			(effects
				(font
					(size 0.7874 0.5842)
					(thickness 0.1524)
				)
				(justify mirror)
			)
		)
		(property "Value" "VAL*"
			(at -0.02032 2.13233 180)
			(unlocked yes)
			(layer "B.Fab")
			(hide yes)
			(effects
				(font
					(size 0.7874 0.5842)
					(thickness 0.1524)
				)
				(justify mirror)
			)
		)
		(property "Tolerance" "TOL*"
			(at -0.044704 3.05435 180)
			(unlocked yes)
			(layer "Cmts.User")
			(hide yes)
			(effects
				(font
					(size 0.7874 0.5842)
					(thickness 0.1524)
				)
				(justify mirror)
			)
		)
		(property "User Part Number" "PARTNUM*"
			(at -0.02032 4.024884 180)
			(unlocked yes)
			(layer "Cmts.User")
			(hide yes)
			(effects
				(font
					(size 0.7874 0.5842)
					(thickness 0.1524)
				)
				(justify mirror)
			)
		)
		(property "Device Type" "RESISTOR-G155-11001-01,1KOHM,1%"
			(at -0.008382 1.210564 180)
			(unlocked yes)
			(layer "B.Fab")
			(hide yes)
			(effects
				(font
					(size 0.7874 0.5842)
					(thickness 0.1524)
				)
				(justify mirror)
			)
		)
		(duplicate_pad_numbers_are_jumpers no)
		(fp_line
			(start 1.143 0.5588)
			(end -1.143 0.5588)
			(stroke
				(width 0.1)
				(type default)
			)
			(layer "B.SilkS")
		)
		(fp_line
			(start 1.143 -0.5588)
			(end 1.143 0.5588)
			(stroke
				(width 0.1)
				(type default)
			)
			(layer "B.SilkS")
		)
		(fp_line
			(start -1.143 0.5588)
			(end -1.143 -0.5588)
			(stroke
				(width 0.1)
				(type default)
			)
			(layer "B.SilkS")
		)
		(fp_line
			(start -1.143 -0.5588)
			(end 1.143 -0.5588)
			(stroke
				(width 0.1)
				(type default)
			)
			(layer "B.SilkS")
		)
		(fp_poly
			(pts
				(xy 1.143 0.5588) (xy -1.143 0.5588) (xy -1.143 -0.5588) (xy 1.143 -0.5588)
			)
			(stroke
				(width 0)
				(type default)
			)
			(fill no)
			(layer "B.CrtYd")
		)
		(fp_line
			(start 0.508 0.3048)
			(end -0.508 0.3048)
			(stroke
				(width 0.1)
				(type default)
			)
			(layer "B.Fab")
		)
		(fp_line
			(start 0.508 -0.3048)
			(end 0.508 0.3048)
			(stroke
				(width 0.1)
				(type default)
			)
			(layer "B.Fab")
		)
		(fp_line
			(start -0.508 0.3048)
			(end -0.508 -0.3048)
			(stroke
				(width 0.1)
				(type default)
			)
			(layer "B.Fab")
		)
		(fp_line
			(start -0.508 -0.3048)
			(end 0.508 -0.3048)
			(stroke
				(width 0.1)
				(type default)
			)
			(layer "B.Fab")
		)
		(pad "1" smd rect
			(at 0.5334 0)
			(size 0.7112 0.6096)
			(layers "B.Cu" "B.Mask" "B.Paste")
			(net "SG")
		)
		(pad "2" smd rect
			(at -0.5334 0)
			(size 0.7112 0.6096)
			(layers "B.Cu" "B.Mask" "B.Paste")
			(net "MUX2_SEL")
		)
		(zone
			(layer "B.Cu")
			(hatch none 0.5)
			(connect_pads
				(clearance 0)
			)
			(min_thickness 0.25)
			(keepout
				(tracks not_allowed)
				(vias allowed)
				(pads allowed)
				(copperpour not_allowed)
				(footprints allowed)
			)
			(placement
				(enabled no)
				(sheetname "")
			)
			(fill
				(thermal_gap 0.5)
				(thermal_bridge_width 0.5)
				(island_removal_mode 0)
			)
			(polygon
				(pts
					(xy 101.3714 -82.5754) (xy 101.3714 -81.9658) (xy 101.5238 -81.9658) (xy 101.5238 -82.5754)
				)
			)
		)
		(zone
			(layer "B.Cu")
			(hatch none 0.5)
			(connect_pads
				(clearance 0)
			)
			(min_thickness 0.25)
			(keepout
				(tracks allowed)
				(vias not_allowed)
				(pads allowed)
				(copperpour not_allowed)
				(footprints allowed)
			)
			(placement
				(enabled no)
				(sheetname "")
			)
			(fill
				(thermal_gap 0.5)
				(thermal_bridge_width 0.5)
				(island_removal_mode 0)
			)
			(polygon
				(pts
					(xy 101.3714 -82.5754) (xy 101.3714 -81.9658) (xy 101.5238 -81.9658) (xy 101.5238 -82.5754)
				)
			)
		)
	)
	(footprint ""
		(layer "B.Cu")
		(at 102.347014 -45.823124)
		(property "Reference" "C106"
			(at 0.014986 1.150874 0)
			(unlocked yes)
			(layer "B.SilkS")
			(effects
				(font
					(size 0.635 0.4064)
					(thickness 0.1524)
				)
				(justify mirror)
			)
		)
		(property "Value" "VAL*"
			(at 0 3.718306 0)
			(unlocked yes)
			(layer "B.Fab")
			(hide yes)
			(effects
				(font
					(size 0.7874 0.5842)
					(thickness 0.127)
				)
				(justify mirror)
			)
		)
		(property "Tolerance" "TOL*"
			(at 0 4.861306 0)
			(unlocked yes)
			(layer "Cmts.User")
			(hide yes)
			(effects
				(font
					(size 0.7874 0.5842)
					(thickness 0.127)
				)
				(justify mirror)
			)
		)
		(property "User Part Number" "PARTNUM*"
			(at 0 2.575306 0)
			(unlocked yes)
			(layer "Cmts.User")
			(hide yes)
			(effects
				(font
					(size 0.7874 0.5842)
					(thickness 0.127)
				)
				(justify mirror)
			)
		)
		(property "Device Type" "CAPACITOR-G105-0B104-CK,0.1UF,A"
			(at 0 1.432306 0)
			(unlocked yes)
			(layer "B.Fab")
			(hide yes)
			(effects
				(font
					(size 0.7874 0.5842)
					(thickness 0.127)
				)
				(justify mirror)
			)
		)
		(duplicate_pad_numbers_are_jumpers no)
		(fp_line
			(start -0.970026 -0.4699)
			(end -0.970026 0.4699)
			(stroke
				(width 0.1)
				(type default)
			)
			(layer "B.SilkS")
		)
		(fp_line
			(start -0.970026 0.4699)
			(end 0.970026 0.4699)
			(stroke
				(width 0.1)
				(type default)
			)
			(layer "B.SilkS")
		)
		(fp_line
			(start 0.970026 -0.4699)
			(end -0.970026 -0.4699)
			(stroke
				(width 0.1)
				(type default)
			)
			(layer "B.SilkS")
		)
		(fp_line
			(start 0.970026 0.4699)
			(end 0.970026 -0.4699)
			(stroke
				(width 0.1)
				(type default)
			)
			(layer "B.SilkS")
		)
		(fp_poly
			(pts
				(xy 0.970026 0.4699) (xy -0.970026 0.4699) (xy -0.970026 -0.4699) (xy 0.970026 -0.4699)
			)
			(stroke
				(width 0)
				(type default)
			)
			(fill no)
			(layer "B.CrtYd")
		)
		(fp_line
			(start -0.508 -0.3048)
			(end -0.508 0.3048)
			(stroke
				(width 0.1)
				(type default)
			)
			(layer "B.Fab")
		)
		(fp_line
			(start -0.508 0.3048)
			(end 0.508 0.3048)
			(stroke
				(width 0.1)
				(type default)
			)
			(layer "B.Fab")
		)
		(fp_line
			(start 0.508 -0.3048)
			(end -0.508 -0.3048)
			(stroke
				(width 0.1)
				(type default)
			)
			(layer "B.Fab")
		)
		(fp_line
			(start 0.508 0.3048)
			(end 0.508 -0.3048)
			(stroke
				(width 0.1)
				(type default)
			)
			(layer "B.Fab")
		)
		(pad "1" smd circle
			(at 0.500126 0 180)
			(size 0.635 0.635)
			(layers "B.Cu" "B.Mask" "B.Paste")
			(net "XP1R8V_FPGA_VCCAUX")
		)
		(pad "2" smd circle
			(at -0.500126 0 180)
			(size 0.635 0.635)
			(layers "B.Cu" "B.Mask" "B.Paste")
			(net "SG")
		)
	)
	(footprint ""
		(layer "B.Cu")
		(at 61.976 -56.896 -90)
		(property "Reference" "U10"
			(at 0.381 2.19837 270)
			(unlocked yes)
			(layer "B.SilkS")
			(effects
				(font
					(size 0.7874 0.5842)
					(thickness 0.1524)
				)
				(justify mirror)
			)
		)
		(property "Value" ""
			(at 0 0 90)
			(layer "B.Fab")
			(effects
				(font
					(size 1.27 1.27)
				)
				(justify mirror)
			)
		)
		(property "User Part Number" "PARTNUM*"
			(at -0.381 2.97307 270)
			(unlocked yes)
			(layer "Cmts.User")
			(hide yes)
			(effects
				(font
					(size 0.7874 0.5842)
					(thickness 0.1524)
				)
				(justify mirror)
			)
		)
		(property "Device Type" "CL5003148A-G220-10019-01"
			(at -0.4064 2.05867 270)
			(unlocked yes)
			(layer "B.Fab")
			(hide yes)
			(effects
				(font
					(size 0.7874 0.5842)
					(thickness 0.1524)
				)
				(justify mirror)
			)
		)
		(duplicate_pad_numbers_are_jumpers no)
		(fp_line
			(start -0.952754 1.32842)
			(end -0.952754 1.069086)
			(stroke
				(width 0.1)
				(type default)
			)
			(layer "B.SilkS")
		)
		(fp_line
			(start 0.952754 1.32842)
			(end -0.952754 1.32842)
			(stroke
				(width 0.1)
				(type default)
			)
			(layer "B.SilkS")
		)
		(fp_line
			(start -1.9304 1.069086)
			(end -1.9304 -1.069086)
			(stroke
				(width 0.1)
				(type default)
			)
			(layer "B.SilkS")
		)
		(fp_line
			(start -0.952754 1.069086)
			(end -1.9304 1.069086)
			(stroke
				(width 0.1)
				(type default)
			)
			(layer "B.SilkS")
		)
		(fp_line
			(start 0.952754 1.069086)
			(end 0.952754 1.32842)
			(stroke
				(width 0.1)
				(type default)
			)
			(layer "B.SilkS")
		)
		(fp_line
			(start 1.9304 1.069086)
			(end 0.952754 1.069086)
			(stroke
				(width 0.1)
				(type default)
			)
			(layer "B.SilkS")
		)
		(fp_line
			(start -1.9304 -1.069086)
			(end -0.952754 -1.069086)
			(stroke
				(width 0.1)
				(type default)
			)
			(layer "B.SilkS")
		)
		(fp_line
			(start -0.952754 -1.069086)
			(end -0.952754 -1.32842)
			(stroke
				(width 0.1)
				(type default)
			)
			(layer "B.SilkS")
		)
		(fp_line
			(start 0.952754 -1.069086)
			(end 1.9304 -1.069086)
			(stroke
				(width 0.1)
				(type default)
			)
			(layer "B.SilkS")
		)
		(fp_line
			(start 1.9304 -1.069086)
			(end 1.9304 1.069086)
			(stroke
				(width 0.1)
				(type default)
			)
			(layer "B.SilkS")
		)
		(fp_line
			(start -0.952754 -1.32842)
			(end 0.952754 -1.32842)
			(stroke
				(width 0.1)
				(type default)
			)
			(layer "B.SilkS")
		)
		(fp_line
			(start 0.952754 -1.32842)
			(end 0.952754 -1.069086)
			(stroke
				(width 0.1)
				(type default)
			)
			(layer "B.SilkS")
		)
		(fp_poly
			(pts
				(arc
					(start 2.577592 -1.13538)
					(mid 2.577592 -0.37338)
					(end 2.577592 -1.13538)
				)
			)
			(stroke
				(width 0)
				(type default)
			)
			(fill yes)
			(layer "B.SilkS")
		)
		(fp_rect
			(start -2.1844 1.58242)
			(end 2.1844 -1.58242)
			(stroke
				(width 0)
				(type default)
			)
			(fill no)
			(layer "B.CrtYd")
		)
		(fp_line
			(start -0.698754 1.07442)
			(end -0.698754 0.774954)
			(stroke
				(width 0.1)
				(type default)
			)
			(layer "B.Fab")
		)
		(fp_line
			(start 0.450088 1.07442)
			(end 0.450088 -1.07442)
			(stroke
				(width 0.1)
				(type default)
			)
			(layer "B.Fab")
		)
		(fp_line
			(start 0.698754 1.07442)
			(end -0.698754 1.07442)
			(stroke
				(width 0.1)
				(type default)
			)
			(layer "B.Fab")
		)
		(fp_line
			(start 0.698754 0.774954)
			(end 0.698754 1.07442)
			(stroke
				(width 0.1)
				(type default)
			)
			(layer "B.Fab")
		)
		(fp_line
			(start 0.698754 0.124968)
			(end 0.698754 0.525018)
			(stroke
				(width 0.1)
				(type default)
			)
			(layer "B.Fab")
		)
		(fp_line
			(start -0.698754 -0.525018)
			(end -0.698754 0.525018)
			(stroke
				(width 0.1)
				(type default)
			)
			(layer "B.Fab")
		)
		(fp_line
			(start 0.698754 -0.525018)
			(end 0.698754 -0.124968)
			(stroke
				(width 0.1)
				(type default)
			)
			(layer "B.Fab")
		)
		(fp_line
			(start 0.698754 -0.774954)
			(end 0.698754 -1.07442)
			(stroke
				(width 0.1)
				(type default)
			)
			(layer "B.Fab")
		)
		(fp_line
			(start -0.698754 -1.07442)
			(end -0.698754 -0.774954)
			(stroke
				(width 0.1)
				(type default)
			)
			(layer "B.Fab")
		)
		(fp_line
			(start -0.450088 -1.07442)
			(end -0.450088 1.07442)
			(stroke
				(width 0.1)
				(type default)
			)
			(layer "B.Fab")
		)
		(fp_line
			(start 0.698754 -1.07442)
			(end -0.698754 -1.07442)
			(stroke
				(width 0.1)
				(type default)
			)
			(layer "B.Fab")
		)
		(fp_rect
			(start -1.198626 0.774954)
			(end -0.6985 0.525018)
			(stroke
				(width 0)
				(type default)
			)
			(fill no)
			(layer "B.Fab")
		)
		(fp_rect
			(start 0.6985 0.774954)
			(end 1.198626 0.525018)
			(stroke
				(width 0)
				(type default)
			)
			(fill no)
			(layer "B.Fab")
		)
		(fp_rect
			(start 0.6985 0.124968)
			(end 1.198626 -0.124968)
			(stroke
				(width 0)
				(type default)
			)
			(fill no)
			(layer "B.Fab")
		)
		(fp_rect
			(start -1.198626 -0.525018)
			(end -0.6985 -0.774954)
			(stroke
				(width 0)
				(type default)
			)
			(fill no)
			(layer "B.Fab")
		)
		(fp_rect
			(start 0.6985 -0.525018)
			(end 1.198626 -0.774954)
			(stroke
				(width 0)
				(type default)
			)
			(fill no)
			(layer "B.Fab")
		)
		(fp_poly
			(pts
				(arc
					(start 2.577592 -1.13538)
					(mid 2.577592 -0.37338)
					(end 2.577592 -1.13538)
				)
			)
			(stroke
				(width 0)
				(type default)
			)
			(fill yes)
			(layer "B.Fab")
		)
		(fp_text user "4"
			(at -1.41605 1.778 0)
			(unlocked yes)
			(layer "B.SilkS")
			(effects
				(font
					(size 0.635 0.4064)
					(thickness 0.1524)
				)
				(justify mirror)
			)
		)
		(fp_text user "3"
			(at 2.64795 1.524 0)
			(unlocked yes)
			(layer "B.SilkS")
			(effects
				(font
					(size 0.635 0.4064)
					(thickness 0.1524)
				)
				(justify mirror)
			)
		)
		(fp_text user "5"
			(at -1.54305 -1.524 0)
			(unlocked yes)
			(layer "B.SilkS")
			(effects
				(font
					(size 0.635 0.4064)
					(thickness 0.1524)
				)
				(justify mirror)
			)
		)
		(fp_text user "3"
			(at 2.05867 0.889 0)
			(unlocked yes)
			(layer "B.Fab")
			(effects
				(font
					(size 0.7874 0.5842)
					(thickness 0.1524)
				)
				(justify mirror)
			)
		)
		(fp_text user "4"
			(at -1.781302 0.36703 0)
			(unlocked yes)
			(layer "B.Fab")
			(effects
				(font
					(size 0.7874 0.5842)
					(thickness 0.1524)
				)
				(justify mirror)
			)
		)
		(fp_text user "5"
			(at -1.75133 -1.007618 0)
			(unlocked yes)
			(layer "B.Fab")
			(effects
				(font
					(size 0.7874 0.5842)
					(thickness 0.1524)
				)
				(justify mirror)
			)
		)
		(pad "1" smd rect
			(at 1.1938 -0.649986)
			(size 0.3302 0.9652)
			(layers "B.Cu" "B.Mask" "B.Paste")
			(net "FPGA_OUT_MACUSBPOWER_EN")
		)
		(pad "2" smd rect
			(at 1.1938 0)
			(size 0.3302 0.9652)
			(layers "B.Cu" "B.Mask" "B.Paste")
			(net "XP5R0V_USB_CONN_DET")
		)
		(pad "3" smd rect
			(at 1.1938 0.649986)
			(size 0.3302 0.9652)
			(layers "B.Cu" "B.Mask" "B.Paste")
			(net "SG")
		)
		(pad "4" smd rect
			(at -1.1938 0.649986)
			(size 0.3302 0.9652)
			(layers "B.Cu" "B.Mask" "B.Paste")
			(net "USB_PWR_EN")
		)
		(pad "5" smd rect
			(at -1.1938 -0.649986)
			(size 0.3302 0.9652)
			(layers "B.Cu" "B.Mask" "B.Paste")
			(net "XP3R3V_FPGA")
		)
		(zone
			(layer "B.Cu")
			(hatch none 0.5)
			(connect_pads
				(clearance 0)
			)
			(min_thickness 0.25)
			(keepout
				(tracks allowed)
				(vias not_allowed)
				(pads allowed)
				(copperpour not_allowed)
				(footprints allowed)
			)
			(placement
				(enabled no)
				(sheetname "")
			)
			(fill
				(thermal_gap 0.5)
				(thermal_bridge_width 0.5)
				(island_removal_mode 0)
			)
			(polygon
				(pts
					(xy 60.9727 -57.531) (xy 60.9727 -56.261) (xy 62.9793 -56.261) (xy 62.9793 -57.531)
				)
			)
		)
	)
	(footprint ""
		(layer "B.Cu")
		(at 25.273 -91.059 90)
		(property "Reference" "R130"
			(at 2.286 -5.11937 270)
			(unlocked yes)
			(layer "B.SilkS")
			(effects
				(font
					(size 0.7874 0.5842)
					(thickness 0.1524)
				)
				(justify mirror)
			)
		)
		(property "Value" "VAL*"
			(at -0.02032 2.13233 90)
			(unlocked yes)
			(layer "B.Fab")
			(hide yes)
			(effects
				(font
					(size 0.7874 0.5842)
					(thickness 0.1524)
				)
				(justify mirror)
			)
		)
		(property "Tolerance" "TOL*"
			(at -0.044704 3.05435 90)
			(unlocked yes)
			(layer "Cmts.User")
			(hide yes)
			(effects
				(font
					(size 0.7874 0.5842)
					(thickness 0.1524)
				)
				(justify mirror)
			)
		)
		(property "User Part Number" "PARTNUM*"
			(at -0.02032 4.024884 90)
			(unlocked yes)
			(layer "Cmts.User")
			(hide yes)
			(effects
				(font
					(size 0.7874 0.5842)
					(thickness 0.1524)
				)
				(justify mirror)
			)
		)
		(property "Device Type" "RESISTOR-G155-11002-01,10KOHM,A"
			(at -0.008382 1.210564 90)
			(unlocked yes)
			(layer "B.Fab")
			(hide yes)
			(effects
				(font
					(size 0.7874 0.5842)
					(thickness 0.1524)
				)
				(justify mirror)
			)
		)
		(duplicate_pad_numbers_are_jumpers no)
		(fp_line
			(start 1.143 -0.5588)
			(end 1.143 0.5588)
			(stroke
				(width 0.1)
				(type default)
			)
			(layer "B.SilkS")
		)
		(fp_line
			(start -1.143 -0.5588)
			(end 1.143 -0.5588)
			(stroke
				(width 0.1)
				(type default)
			)
			(layer "B.SilkS")
		)
		(fp_line
			(start 1.143 0.5588)
			(end -1.143 0.5588)
			(stroke
				(width 0.1)
				(type default)
			)
			(layer "B.SilkS")
		)
		(fp_line
			(start -1.143 0.5588)
			(end -1.143 -0.5588)
			(stroke
				(width 0.1)
				(type default)
			)
			(layer "B.SilkS")
		)
		(fp_poly
			(pts
				(xy 1.143 0.5588) (xy -1.143 0.5588) (xy -1.143 -0.5588) (xy 1.143 -0.5588)
			)
			(stroke
				(width 0)
				(type default)
			)
			(fill no)
			(layer "B.CrtYd")
		)
		(fp_line
			(start 0.508 -0.3048)
			(end 0.508 0.3048)
			(stroke
				(width 0.1)
				(type default)
			)
			(layer "B.Fab")
		)
		(fp_line
			(start -0.508 -0.3048)
			(end 0.508 -0.3048)
			(stroke
				(width 0.1)
				(type default)
			)
			(layer "B.Fab")
		)
		(fp_line
			(start 0.508 0.3048)
			(end -0.508 0.3048)
			(stroke
				(width 0.1)
				(type default)
			)
			(layer "B.Fab")
		)
		(fp_line
			(start -0.508 0.3048)
			(end -0.508 -0.3048)
			(stroke
				(width 0.1)
				(type default)
			)
			(layer "B.Fab")
		)
		(pad "1" smd rect
			(at 0.5334 0 270)
			(size 0.7112 0.6096)
			(layers "B.Cu" "B.Mask" "B.Paste")
			(net "FT_USB_DETECT")
		)
		(pad "2" smd rect
			(at -0.5334 0 270)
			(size 0.7112 0.6096)
			(layers "B.Cu" "B.Mask" "B.Paste")
			(net "SG")
		)
		(zone
			(layer "B.Cu")
			(hatch none 0.5)
			(connect_pads
				(clearance 0)
			)
			(min_thickness 0.25)
			(keepout
				(tracks not_allowed)
				(vias allowed)
				(pads allowed)
				(copperpour not_allowed)
				(footprints allowed)
			)
			(placement
				(enabled no)
				(sheetname "")
			)
			(fill
				(thermal_gap 0.5)
				(thermal_bridge_width 0.5)
				(island_removal_mode 0)
			)
			(polygon
				(pts
					(xy 25.5778 -91.1352) (xy 24.9682 -91.1352) (xy 24.9682 -90.9828) (xy 25.5778 -90.9828)
				)
			)
		)
		(zone
			(layer "B.Cu")
			(hatch none 0.5)
			(connect_pads
				(clearance 0)
			)
			(min_thickness 0.25)
			(keepout
				(tracks allowed)
				(vias not_allowed)
				(pads allowed)
				(copperpour not_allowed)
				(footprints allowed)
			)
			(placement
				(enabled no)
				(sheetname "")
			)
			(fill
				(thermal_gap 0.5)
				(thermal_bridge_width 0.5)
				(island_removal_mode 0)
			)
			(polygon
				(pts
					(xy 25.5778 -91.1352) (xy 24.9682 -91.1352) (xy 24.9682 -90.9828) (xy 25.5778 -90.9828)
				)
			)
		)
	)
)
